# TIMECARD (Time Appliance Project (Time Card)) — schematic netlist excerpt (pin names and nets, part order shuffled) for the footprints in the layout excerpt that follows; sources: Cadence DE-HDL packaged netlist, KiCad conversion of R4006-B0001-02_R01.brd

C143  CAPACITOR  47UF 4V 20%  pkg SMC_0805R_H057  page 14 : \1\ = XP1R2V_FPGA ; \2\ = SG
R215  RESISTOR  10KOHM 1%  pkg SMC_0402R_H016  page 10 : \1\ = XP3R3V_FPGA ; \2\ = FPGA_BRD_REV1

(kicad_pcb
	(version 20260206)
	(generator "pcbnew")
	(generator_version "10.0")
	(general
		(thickness 1.6)
		(legacy_teardrops no)
	)
	(paper "A4")
	(title_block
		(title "timecard-production-celestica-r4006 — R4006-B0001-02_R01.brd")
		(comment 1 "Time Appliance Project (Time Card) / footprints 1083-1084 of 1113")
	)
	(layers
		(0 "F.Cu" signal "TOP")
		(4 "In1.Cu" signal "L02_GND1")
		(6 "In2.Cu" signal "L03_SIG1")
		(8 "In3.Cu" signal "L04_GND2")
		(10 "In4.Cu" signal "L05_VCC1")
		(12 "In5.Cu" signal "L06_VCC2")
		(14 "In6.Cu" signal "L07_GND3")
		(16 "In7.Cu" signal "L08_SIG2")
		(18 "In8.Cu" signal "L09_GND4")
		(2 "B.Cu" signal "BOTTOM")
		(9 "F.Adhes" user "F.Adhesive")
		(11 "B.Adhes" user "B.Adhesive")
		(13 "F.Paste" user "Package Geometry/Pastemask Top")
		(15 "B.Paste" user "Package Geometry/Pastemask Bottom")
		(5 "F.SilkS" user "Ref Des/Silkscreen Top")
		(7 "B.SilkS" user "Ref Des/Silkscreen Bottom")
		(1 "F.Mask" user "Board Geometry/Soldermask Top")
		(3 "B.Mask" user "Board Geometry/Soldermask Bottom")
		(17 "Dwgs.User" user "User.Drawings")
		(19 "Cmts.User" user "User.Comments")
		(21 "Eco1.User" user "User.Eco1")
		(23 "Eco2.User" user "User.Eco2")
		(25 "Edge.Cuts" user "Board Geometry/Outline")
		(27 "Margin" user)
		(31 "F.CrtYd" user "Package Geometry/Place Bound Top")
		(29 "B.CrtYd" user "Package Geometry/Place Bound Bottom")
		(35 "F.Fab" user "Ref Des/Assembly Top")
		(33 "B.Fab" user "Ref Des/Assembly Bottom")
	)
	(footprint ""
		(layer "B.Cu")
		(at 87.884 -34.163 90)
		(property "Reference" "C143"
			(at -3.429 -0.03937 270)
			(unlocked yes)
			(layer "B.SilkS")
			(effects
				(font
					(size 0.7874 0.5842)
					(thickness 0.1524)
				)
				(justify mirror)
			)
		)
		(property "Value" "VAL*"
			(at -0.0762 3.134106 90)
			(unlocked yes)
			(layer "B.Fab")
			(hide yes)
			(effects
				(font
					(size 0.7874 0.5842)
					(thickness 0.1524)
				)
				(justify mirror)
			)
		)
		(property "Tolerance" "TOL*"
			(at -0.0762 4.048506 90)
			(unlocked yes)
			(layer "Cmts.User")
			(hide yes)
			(effects
				(font
					(size 0.7874 0.5842)
					(thickness 0.1524)
				)
				(justify mirror)
			)
		)
		(property "User Part Number" "PARTNUM*"
			(at -0.1016 5.013706 90)
			(unlocked yes)
			(layer "Cmts.User")
			(hide yes)
			(effects
				(font
					(size 0.7874 0.5842)
					(thickness 0.1524)
				)
				(justify mirror)
			)
		)
		(property "Device Type" "CAPACITOR-G107-0F476-AM,47UF,2A"
			(at -0.0508 2.194306 90)
			(unlocked yes)
			(layer "B.Fab")
			(hide yes)
			(effects
				(font
					(size 0.7874 0.5842)
					(thickness 0.1524)
				)
				(justify mirror)
			)
		)
		(duplicate_pad_numbers_are_jumpers no)
		(fp_line
			(start 1.5748 -0.9398)
			(end 1.5748 0.9398)
			(stroke
				(width 0.1)
				(type default)
			)
			(layer "B.SilkS")
		)
		(fp_line
			(start -1.5748 -0.9398)
			(end 1.5748 -0.9398)
			(stroke
				(width 0.1)
				(type default)
			)
			(layer "B.SilkS")
		)
		(fp_line
			(start 1.5748 0.9398)
			(end -1.5748 0.9398)
			(stroke
				(width 0.1)
				(type default)
			)
			(layer "B.SilkS")
		)
		(fp_line
			(start -1.5748 0.9398)
			(end -1.5748 -0.9398)
			(stroke
				(width 0.1)
				(type default)
			)
			(layer "B.SilkS")
		)
		(fp_rect
			(start 1.5748 -0.9398)
			(end -1.5748 0.9398)
			(stroke
				(width 0)
				(type default)
			)
			(fill no)
			(layer "B.CrtYd")
		)
		(fp_line
			(start 1.016 -0.635)
			(end 1.016 0.635)
			(stroke
				(width 0.1)
				(type default)
			)
			(layer "B.Fab")
		)
		(fp_line
			(start -1.016 -0.635)
			(end 1.016 -0.635)
			(stroke
				(width 0.1)
				(type default)
			)
			(layer "B.Fab")
		)
		(fp_line
			(start 1.016 0.635)
			(end -1.016 0.635)
			(stroke
				(width 0.1)
				(type default)
			)
			(layer "B.Fab")
		)
		(fp_line
			(start -1.016 0.635)
			(end -1.016 -0.635)
			(stroke
				(width 0.1)
				(type default)
			)
			(layer "B.Fab")
		)
		(pad "1" smd rect
			(at 0.8382 0 270)
			(size 0.9652 1.3716)
			(layers "B.Cu" "B.Mask" "B.Paste")
			(net "XP1R2V_FPGA")
		)
		(pad "2" smd rect
			(at -0.8382 0 270)
			(size 0.9652 1.3716)
			(layers "B.Cu" "B.Mask" "B.Paste")
			(net "SG")
		)
		(zone
			(layer "B.Cu")
			(hatch none 0.5)
			(connect_pads
				(clearance 0)
			)
			(min_thickness 0.25)
			(keepout
				(tracks allowed)
				(vias not_allowed)
				(pads allowed)
				(copperpour not_allowed)
				(footprints allowed)
			)
			(placement
				(enabled no)
				(sheetname "")
			)
			(fill
				(thermal_gap 0.5)
				(thermal_bridge_width 0.5)
				(island_removal_mode 0)
			)
			(polygon
				(pts
					(xy 87.249 -34.3916) (xy 87.249 -33.9344) (xy 88.519 -33.9344) (xy 88.519 -34.3916)
				)
			)
		)
	)
	(footprint ""
		(layer "B.Cu")
		(at 115.062 -61.976 90)
		(property "Reference" "R215"
			(at 3.429 0.08763 270)
			(unlocked yes)
			(layer "B.SilkS")
			(effects
				(font
					(size 0.7874 0.5842)
					(thickness 0.1524)
				)
				(justify mirror)
			)
		)
		(property "Value" "VAL*"
			(at -0.02032 2.13233 90)
			(unlocked yes)
			(layer "B.Fab")
			(hide yes)
			(effects
				(font
					(size 0.7874 0.5842)
					(thickness 0.1524)
				)
				(justify mirror)
			)
		)
		(property "Device Type" "RESISTOR-G155-11002-01,10KOHM,A"
			(at -0.008382 1.210564 90)
			(unlocked yes)
			(layer "B.Fab")
			(hide yes)
			(effects
				(font
					(size 0.7874 0.5842)
					(thickness 0.1524)
				)
				(justify mirror)
			)
		)
		(property "User Part Number" "PARTNUM*"
			(at -0.02032 4.024884 90)
			(unlocked yes)
			(layer "Cmts.User")
			(hide yes)
			(effects
				(font
					(size 0.7874 0.5842)
					(thickness 0.1524)
				)
				(justify mirror)
			)
		)
		(property "Tolerance" "TOL*"
			(at -0.044704 3.05435 90)
			(unlocked yes)
			(layer "Cmts.User")
			(hide yes)
			(effects
				(font
					(size 0.7874 0.5842)
					(thickness 0.1524)
				)
				(justify mirror)
			)
		)
		(duplicate_pad_numbers_are_jumpers no)
		(fp_line
			(start 1.143 -0.5588)
			(end 1.143 0.5588)
			(stroke
				(width 0.1)
				(type default)
			)
			(layer "B.SilkS")
		)
		(fp_line
			(start -1.143 -0.5588)
			(end 1.143 -0.5588)
			(stroke
				(width 0.1)
				(type default)
			)
			(layer "B.SilkS")
		)
		(fp_line
			(start 1.143 0.5588)
			(end -1.143 0.5588)
			(stroke
				(width 0.1)
				(type default)
			)
			(layer "B.SilkS")
		)
		(fp_line
			(start -1.143 0.5588)
			(end -1.143 -0.5588)
			(stroke
				(width 0.1)
				(type default)
			)
			(layer "B.SilkS")
		)
		(fp_rect
			(start -1.143 0.5588)
			(end 1.143 -0.5588)
			(stroke
				(width 0)
				(type default)
			)
			(fill no)
			(layer "B.CrtYd")
		)
		(fp_line
			(start 0.508 -0.3048)
			(end 0.508 0.3048)
			(stroke
				(width 0.1)
				(type default)
			)
			(layer "B.Fab")
		)
		(fp_line
			(start -0.508 -0.3048)
			(end 0.508 -0.3048)
			(stroke
				(width 0.1)
				(type default)
			)
			(layer "B.Fab")
		)
		(fp_line
			(start 0.508 0.3048)
			(end -0.508 0.3048)
			(stroke
				(width 0.1)
				(type default)
			)
			(layer "B.Fab")
		)
		(fp_line
			(start -0.508 0.3048)
			(end -0.508 -0.3048)
			(stroke
				(width 0.1)
				(type default)
			)
			(layer "B.Fab")
		)
		(pad "1" smd rect
			(at 0.5334 0 270)
			(size 0.7112 0.6096)
			(layers "B.Cu" "B.Mask" "B.Paste")
			(net "XP3R3V_FPGA")
		)
		(pad "2" smd rect
			(at -0.5334 0 270)
			(size 0.7112 0.6096)
			(layers "B.Cu" "B.Mask" "B.Paste")
			(net "FPGA_BRD_REV1")
		)
		(zone
			(layer "B.Cu")
			(hatch none 0.5)
			(connect_pads
				(clearance 0)
			)
			(min_thickness 0.25)
			(keepout
				(tracks allowed)
				(vias not_allowed)
				(pads allowed)
				(copperpour not_allowed)
				(footprints allowed)
			)
			(placement
				(enabled no)
				(sheetname "")
			)
			(fill
				(thermal_gap 0.5)
				(thermal_bridge_width 0.5)
				(island_removal_mode 0)
			)
			(polygon
				(pts
					(xy 115.3668 -61.8998) (xy 115.3668 -62.0522) (xy 114.7572 -62.0522) (xy 114.7572 -61.8998)
				)
			)
		)
	)
)
